(kicad_pcb
	(version 20260206)
	(generator "pcbnew")
	(generator_version "10.0")
	(general
		(thickness 1.6)
		(legacy_teardrops no)
	)
	(paper "A4")
	(title_block
		(title "04192023_DAF0TMB3IC0_F0TG_MB_C_brd_V02_OCP.brd")
		(comment 1 "Grand Teton / footprints 1835-1841 of 8354")
	)
	(layers
		(0 "F.Cu" signal "TOP")
		(4 "In1.Cu" signal "GND")
		(6 "In2.Cu" signal "IN1")
		(8 "In3.Cu" signal "GND1")
		(10 "In4.Cu" signal "IN2")
		(12 "In5.Cu" signal "GND2")
		(14 "In6.Cu" signal "IN3")
		(16 "In7.Cu" signal "GND3")
		(18 "In8.Cu" signal "VCC")
		(20 "In9.Cu" signal "VCC1")
		(22 "In10.Cu" signal "GND4")
		(24 "In11.Cu" signal "IN4")
		(26 "In12.Cu" signal "GND5")
		(28 "In13.Cu" signal "IN5")
		(30 "In14.Cu" signal "GND6")
		(32 "In15.Cu" signal "IN6")
		(34 "In16.Cu" signal "GND7")
		(2 "B.Cu" signal "BOTTOM")
		(9 "F.Adhes" user "F.Adhesive")
		(11 "B.Adhes" user "B.Adhesive")
		(13 "F.Paste" user "Package Geometry/Pastemask Top")
		(15 "B.Paste" user "Package Geometry/Pastemask Bottom")
		(5 "F.SilkS" user "Ref Des/Silkscreen Top")
		(7 "B.SilkS" user "Ref Des/Silkscreen Bottom")
		(1 "F.Mask" user "Board Geometry/Soldermask Top")
		(3 "B.Mask" user "Board Geometry/Soldermask Bottom")
		(17 "Dwgs.User" user "User.Drawings")
		(19 "Cmts.User" user "User.Comments")
		(21 "Eco1.User" user "User.Eco1")
		(23 "Eco2.User" user "User.Eco2")
		(25 "Edge.Cuts" user "Board Geometry/Outline")
		(27 "Margin" user)
		(31 "F.CrtYd" user "Package Geometry/Place Bound Top")
		(29 "B.CrtYd" user "Package Geometry/Place Bound Bottom")
		(35 "F.Fab" user "Ref Des/Assembly Top")
		(33 "B.Fab" user "Ref Des/Assembly Bottom")
	)
	(footprint ""
		(layer "F.Cu")
		(at 148.641562 -41.746424)
		(property "Reference" "R1702"
			(at 0 0 0)
			(layer "F.SilkS")
			(hide yes)
			(effects
				(font
					(size 1.27 1.27)
				)
			)
		)
		(property "Value" ""
			(at 0 0 0)
			(layer "F.Fab")
			(effects
				(font
					(size 1.27 1.27)
				)
			)
		)
		(duplicate_pad_numbers_are_jumpers no)
		(fp_line
			(start -0.7874 -0.4064)
			(end 0.7874 -0.4064)
			(stroke
				(width 0.1524)
				(type default)
			)
			(layer "F.SilkS")
		)
		(fp_line
			(start -0.7874 0.4064)
			(end -0.7874 -0.4064)
			(stroke
				(width 0.1524)
				(type default)
			)
			(layer "F.SilkS")
		)
		(fp_line
			(start 0.7874 -0.4064)
			(end 0.7874 0.4064)
			(stroke
				(width 0.1524)
				(type default)
			)
			(layer "F.SilkS")
		)
		(fp_line
			(start 0.7874 0.4064)
			(end -0.7874 0.4064)
			(stroke
				(width 0.1524)
				(type default)
			)
			(layer "F.SilkS")
		)
		(fp_line
			(start -0.67945 -0.305054)
			(end -0.12065 -0.305054)
			(stroke
				(width 0.1)
				(type default)
			)
			(layer "F.Fab")
		)
		(fp_line
			(start -0.67945 0.3048)
			(end -0.67945 -0.305054)
			(stroke
				(width 0.1)
				(type default)
			)
			(layer "F.Fab")
		)
		(fp_line
			(start -0.12065 -0.305054)
			(end -0.12065 -0.2794)
			(stroke
				(width 0.1)
				(type default)
			)
			(layer "F.Fab")
		)
		(fp_line
			(start -0.12065 -0.2794)
			(end 0.12065 -0.2794)
			(stroke
				(width 0.1)
				(type default)
			)
			(layer "F.Fab")
		)
		(fp_line
			(start -0.12065 0.2794)
			(end -0.12065 0.3048)
			(stroke
				(width 0.1)
				(type default)
			)
			(layer "F.Fab")
		)
		(fp_line
			(start -0.12065 0.3048)
			(end -0.67945 0.3048)
			(stroke
				(width 0.1)
				(type default)
			)
			(layer "F.Fab")
		)
		(fp_line
			(start 0.120396 0.2794)
			(end -0.12065 0.2794)
			(stroke
				(width 0.1)
				(type default)
			)
			(layer "F.Fab")
		)
		(fp_line
			(start 0.120396 0.3048)
			(end 0.120396 0.2794)
			(stroke
				(width 0.1)
				(type default)
			)
			(layer "F.Fab")
		)
		(fp_line
			(start 0.12065 -0.3048)
			(end 0.67945 -0.3048)
			(stroke
				(width 0.1)
				(type default)
			)
			(layer "F.Fab")
		)
		(fp_line
			(start 0.12065 -0.2794)
			(end 0.12065 -0.3048)
			(stroke
				(width 0.1)
				(type default)
			)
			(layer "F.Fab")
		)
		(fp_line
			(start 0.67945 -0.3048)
			(end 0.67945 0.3048)
			(stroke
				(width 0.1)
				(type default)
			)
			(layer "F.Fab")
		)
		(fp_line
			(start 0.67945 0.3048)
			(end 0.120396 0.3048)
			(stroke
				(width 0.1)
				(type default)
			)
			(layer "F.Fab")
		)
		(pad "1" smd circle
			(at -0.40005 0)
			(size 0 0)
			(layers "F.Cu" "F.Mask" "F.Paste")
			(net "P1V8_AUX")
		)
		(pad "2" smd circle
			(at 0.40005 0)
			(size 0 0)
			(layers "F.Cu" "F.Mask" "F.Paste")
			(net "SMB_M2_P1_1V8AUX_SDA_R")
		)
	)
	(footprint ""
		(layer "F.Cu")
		(at 200.476358 -387.560566 90)
		(property "Reference" "PC1789"
			(at 0 0 90)
			(layer "F.SilkS")
			(hide yes)
			(effects
				(font
					(size 1.27 1.27)
				)
			)
		)
		(property "Value" ""
			(at 0 0 90)
			(layer "F.Fab")
			(effects
				(font
					(size 1.27 1.27)
				)
			)
		)
		(duplicate_pad_numbers_are_jumpers no)
		(fp_line
			(start 0.7874 -0.4064)
			(end 0.7874 0.4064)
			(stroke
				(width 0.1524)
				(type default)
			)
			(layer "F.SilkS")
		)
		(fp_line
			(start -0.7874 -0.4064)
			(end 0.7874 -0.4064)
			(stroke
				(width 0.1524)
				(type default)
			)
			(layer "F.SilkS")
		)
		(fp_line
			(start 0.7874 0.4064)
			(end -0.7874 0.4064)
			(stroke
				(width 0.1524)
				(type default)
			)
			(layer "F.SilkS")
		)
		(fp_line
			(start -0.7874 0.4064)
			(end -0.7874 -0.4064)
			(stroke
				(width 0.1524)
				(type default)
			)
			(layer "F.SilkS")
		)
		(fp_line
			(start -0.12065 -0.305054)
			(end -0.12065 -0.2794)
			(stroke
				(width 0.1)
				(type default)
			)
			(layer "F.Fab")
		)
		(fp_line
			(start -0.67945 -0.305054)
			(end -0.12065 -0.305054)
			(stroke
				(width 0.1)
				(type default)
			)
			(layer "F.Fab")
		)
		(fp_line
			(start 0.67945 -0.3048)
			(end 0.67945 0.3048)
			(stroke
				(width 0.1)
				(type default)
			)
			(layer "F.Fab")
		)
		(fp_line
			(start 0.12065 -0.3048)
			(end 0.67945 -0.3048)
			(stroke
				(width 0.1)
				(type default)
			)
			(layer "F.Fab")
		)
		(fp_line
			(start 0.12065 -0.2794)
			(end 0.12065 -0.3048)
			(stroke
				(width 0.1)
				(type default)
			)
			(layer "F.Fab")
		)
		(fp_line
			(start -0.12065 -0.2794)
			(end 0.12065 -0.2794)
			(stroke
				(width 0.1)
				(type default)
			)
			(layer "F.Fab")
		)
		(fp_line
			(start 0.120396 0.2794)
			(end -0.12065 0.2794)
			(stroke
				(width 0.1)
				(type default)
			)
			(layer "F.Fab")
		)
		(fp_line
			(start -0.12065 0.2794)
			(end -0.12065 0.3048)
			(stroke
				(width 0.1)
				(type default)
			)
			(layer "F.Fab")
		)
		(fp_line
			(start 0.67945 0.3048)
			(end 0.120396 0.3048)
			(stroke
				(width 0.1)
				(type default)
			)
			(layer "F.Fab")
		)
		(fp_line
			(start 0.120396 0.3048)
			(end 0.120396 0.2794)
			(stroke
				(width 0.1)
				(type default)
			)
			(layer "F.Fab")
		)
		(fp_line
			(start -0.12065 0.3048)
			(end -0.67945 0.3048)
			(stroke
				(width 0.1)
				(type default)
			)
			(layer "F.Fab")
		)
		(fp_line
			(start -0.67945 0.3048)
			(end -0.67945 -0.305054)
			(stroke
				(width 0.1)
				(type default)
			)
			(layer "F.Fab")
		)
		(pad "1" smd circle
			(at -0.40005 0 90)
			(size 0 0)
			(layers "F.Cu" "F.Mask" "F.Paste")
			(net "P12V_AUX")
		)
		(pad "2" smd circle
			(at 0.40005 0 90)
			(size 0 0)
			(layers "F.Cu" "F.Mask" "F.Paste")
			(net "GND")
		)
	)
	(footprint ""
		(layer "F.Cu")
		(at 57.75833 -17.623536 90)
		(property "Reference" "C708"
			(at 0 0 90)
			(layer "F.SilkS")
			(hide yes)
			(effects
				(font
					(size 1.27 1.27)
				)
			)
		)
		(property "Value" ""
			(at 0 0 90)
			(layer "F.Fab")
			(effects
				(font
					(size 1.27 1.27)
				)
			)
		)
		(duplicate_pad_numbers_are_jumpers no)
		(fp_line
			(start 0.299974 -0.150114)
			(end 0.299974 0.150114)
			(stroke
				(width 0.1)
				(type default)
			)
			(layer "F.Fab")
		)
		(fp_line
			(start -0.299974 -0.150114)
			(end 0.299974 -0.150114)
			(stroke
				(width 0.1)
				(type default)
			)
			(layer "F.Fab")
		)
		(fp_line
			(start 0.299974 0.150114)
			(end -0.299974 0.150114)
			(stroke
				(width 0.1)
				(type default)
			)
			(layer "F.Fab")
		)
		(fp_line
			(start -0.299974 0.150114)
			(end -0.299974 -0.150114)
			(stroke
				(width 0.1)
				(type default)
			)
			(layer "F.Fab")
		)
		(pad "1" smd rect
			(at -0.2667 0 90)
			(size 0.3048 0.381)
			(layers "F.Cu" "F.Mask" "F.Paste")
			(net "P5E_CPU1_G1_TX_C_DN<0>")
		)
		(pad "2" smd rect
			(at 0.2667 0 90)
			(size 0.3048 0.381)
			(layers "F.Cu" "F.Mask" "F.Paste")
			(net "P5E_CPU1_G1_TX_DN<0>")
		)
	)
	(footprint ""
		(layer "F.Cu")
		(at 191.055498 -428.496476 90)
		(property "Reference" "R2950"
			(at 0 0 90)
			(layer "F.SilkS")
			(hide yes)
			(effects
				(font
					(size 1.27 1.27)
				)
			)
		)
		(property "Value" ""
			(at 0 0 90)
			(layer "F.Fab")
			(effects
				(font
					(size 1.27 1.27)
				)
			)
		)
		(duplicate_pad_numbers_are_jumpers no)
		(fp_line
			(start 0.7874 -0.4064)
			(end 0.7874 0.4064)
			(stroke
				(width 0.1524)
				(type default)
			)
			(layer "F.SilkS")
		)
		(fp_line
			(start -0.7874 -0.4064)
			(end 0.7874 -0.4064)
			(stroke
				(width 0.1524)
				(type default)
			)
			(layer "F.SilkS")
		)
		(fp_line
			(start 0.7874 0.4064)
			(end -0.7874 0.4064)
			(stroke
				(width 0.1524)
				(type default)
			)
			(layer "F.SilkS")
		)
		(fp_line
			(start -0.7874 0.4064)
			(end -0.7874 -0.4064)
			(stroke
				(width 0.1524)
				(type default)
			)
			(layer "F.SilkS")
		)
		(fp_line
			(start -0.12065 -0.305054)
			(end -0.12065 -0.2794)
			(stroke
				(width 0.1)
				(type default)
			)
			(layer "F.Fab")
		)
		(fp_line
			(start -0.67945 -0.305054)
			(end -0.12065 -0.305054)
			(stroke
				(width 0.1)
				(type default)
			)
			(layer "F.Fab")
		)
		(fp_line
			(start 0.67945 -0.3048)
			(end 0.67945 0.3048)
			(stroke
				(width 0.1)
				(type default)
			)
			(layer "F.Fab")
		)
		(fp_line
			(start 0.12065 -0.3048)
			(end 0.67945 -0.3048)
			(stroke
				(width 0.1)
				(type default)
			)
			(layer "F.Fab")
		)
		(fp_line
			(start 0.12065 -0.2794)
			(end 0.12065 -0.3048)
			(stroke
				(width 0.1)
				(type default)
			)
			(layer "F.Fab")
		)
		(fp_line
			(start -0.12065 -0.2794)
			(end 0.12065 -0.2794)
			(stroke
				(width 0.1)
				(type default)
			)
			(layer "F.Fab")
		)
		(fp_line
			(start 0.120396 0.2794)
			(end -0.12065 0.2794)
			(stroke
				(width 0.1)
				(type default)
			)
			(layer "F.Fab")
		)
		(fp_line
			(start -0.12065 0.2794)
			(end -0.12065 0.3048)
			(stroke
				(width 0.1)
				(type default)
			)
			(layer "F.Fab")
		)
		(fp_line
			(start 0.67945 0.3048)
			(end 0.120396 0.3048)
			(stroke
				(width 0.1)
				(type default)
			)
			(layer "F.Fab")
		)
		(fp_line
			(start 0.120396 0.3048)
			(end 0.120396 0.2794)
			(stroke
				(width 0.1)
				(type default)
			)
			(layer "F.Fab")
		)
		(fp_line
			(start -0.12065 0.3048)
			(end -0.67945 0.3048)
			(stroke
				(width 0.1)
				(type default)
			)
			(layer "F.Fab")
		)
		(fp_line
			(start -0.67945 0.3048)
			(end -0.67945 -0.305054)
			(stroke
				(width 0.1)
				(type default)
			)
			(layer "F.Fab")
		)
		(pad "1" smd circle
			(at -0.40005 0 90)
			(size 0 0)
			(layers "F.Cu" "F.Mask" "F.Paste")
			(net "P3V3_AUX")
		)
		(pad "2" smd circle
			(at 0.40005 0 90)
			(size 0 0)
			(layers "F.Cu" "F.Mask" "F.Paste")
			(net "FM_PDB_BUF_EN_R1_N")
		)
	)
	(footprint ""
		(layer "F.Cu")
		(at 302.133 -355.854 180)
		(property "Reference" "C303"
			(at 0 0 180)
			(layer "F.SilkS")
			(hide yes)
			(effects
				(font
					(size 1.27 1.27)
				)
			)
		)
		(property "Value" ""
			(at 0 0 180)
			(layer "F.Fab")
			(effects
				(font
					(size 1.27 1.27)
				)
			)
		)
		(duplicate_pad_numbers_are_jumpers no)
		(fp_line
			(start 0.7874 0.4064)
			(end -0.7874 0.4064)
			(stroke
				(width 0.1524)
				(type default)
			)
			(layer "F.SilkS")
		)
		(fp_line
			(start 0.7874 -0.4064)
			(end 0.7874 0.4064)
			(stroke
				(width 0.1524)
				(type default)
			)
			(layer "F.SilkS")
		)
		(fp_line
			(start -0.7874 0.4064)
			(end -0.7874 -0.4064)
			(stroke
				(width 0.1524)
				(type default)
			)
			(layer "F.SilkS")
		)
		(fp_line
			(start -0.7874 -0.4064)
			(end 0.7874 -0.4064)
			(stroke
				(width 0.1524)
				(type default)
			)
			(layer "F.SilkS")
		)
		(fp_line
			(start 0.67945 0.3048)
			(end 0.120396 0.3048)
			(stroke
				(width 0.1)
				(type default)
			)
			(layer "F.Fab")
		)
		(fp_line
			(start 0.67945 -0.3048)
			(end 0.67945 0.3048)
			(stroke
				(width 0.1)
				(type default)
			)
			(layer "F.Fab")
		)
		(fp_line
			(start 0.12065 -0.2794)
			(end 0.12065 -0.3048)
			(stroke
				(width 0.1)
				(type default)
			)
			(layer "F.Fab")
		)
		(fp_line
			(start 0.12065 -0.3048)
			(end 0.67945 -0.3048)
			(stroke
				(width 0.1)
				(type default)
			)
			(layer "F.Fab")
		)
		(fp_line
			(start 0.120396 0.3048)
			(end 0.120396 0.2794)
			(stroke
				(width 0.1)
				(type default)
			)
			(layer "F.Fab")
		)
		(fp_line
			(start 0.120396 0.2794)
			(end -0.12065 0.2794)
			(stroke
				(width 0.1)
				(type default)
			)
			(layer "F.Fab")
		)
		(fp_line
			(start -0.12065 0.3048)
			(end -0.67945 0.3048)
			(stroke
				(width 0.1)
				(type default)
			)
			(layer "F.Fab")
		)
		(fp_line
			(start -0.12065 0.2794)
			(end -0.12065 0.3048)
			(stroke
				(width 0.1)
				(type default)
			)
			(layer "F.Fab")
		)
		(fp_line
			(start -0.12065 -0.2794)
			(end 0.12065 -0.2794)
			(stroke
				(width 0.1)
				(type default)
			)
			(layer "F.Fab")
		)
		(fp_line
			(start -0.12065 -0.305054)
			(end -0.12065 -0.2794)
			(stroke
				(width 0.1)
				(type default)
			)
			(layer "F.Fab")
		)
		(fp_line
			(start -0.67945 0.3048)
			(end -0.67945 -0.305054)
			(stroke
				(width 0.1)
				(type default)
			)
			(layer "F.Fab")
		)
		(fp_line
			(start -0.67945 -0.305054)
			(end -0.12065 -0.305054)
			(stroke
				(width 0.1)
				(type default)
			)
			(layer "F.Fab")
		)
		(pad "1" smd circle
			(at -0.40005 0 180)
			(size 0 0)
			(layers "F.Cu" "F.Mask" "F.Paste")
			(net "SVID_PVDDCR_CPU1_P0_SVTO")
		)
		(pad "2" smd circle
			(at 0.40005 0 180)
			(size 0 0)
			(layers "F.Cu" "F.Mask" "F.Paste")
			(net "GND")
		)
	)
	(footprint ""
		(layer "F.Cu")
		(at 103.190294 -385.09448 180)
		(property "Reference" "L31"
			(at 0 0 180)
			(layer "F.SilkS")
			(hide yes)
			(effects
				(font
					(size 1.27 1.27)
				)
			)
		)
		(property "Value" ""
			(at 0 0 180)
			(layer "F.Fab")
			(effects
				(font
					(size 1.27 1.27)
				)
			)
		)
		(duplicate_pad_numbers_are_jumpers no)
		(fp_line
			(start 0.762 0.381)
			(end -0.762 0.381)
			(stroke
				(width 0.1524)
				(type default)
			)
			(layer "F.SilkS")
		)
		(fp_line
			(start 0.762 -0.381)
			(end 0.762 0.381)
			(stroke
				(width 0.1524)
				(type default)
			)
			(layer "F.SilkS")
		)
		(fp_line
			(start -0.762 0.381)
			(end -0.762 -0.381)
			(stroke
				(width 0.1524)
				(type default)
			)
			(layer "F.SilkS")
		)
		(fp_line
			(start -0.762 -0.381)
			(end 0.762 -0.381)
			(stroke
				(width 0.1524)
				(type default)
			)
			(layer "F.SilkS")
		)
		(fp_line
			(start 0.680466 0.306324)
			(end 0.118364 0.306324)
			(stroke
				(width 0.1)
				(type default)
			)
			(layer "F.Fab")
		)
		(fp_line
			(start 0.680466 -0.306324)
			(end 0.680466 0.306324)
			(stroke
				(width 0.1)
				(type default)
			)
			(layer "F.Fab")
		)
		(fp_line
			(start 0.118872 -0.2794)
			(end 0.118872 -0.306324)
			(stroke
				(width 0.1)
				(type default)
			)
			(layer "F.Fab")
		)
		(fp_line
			(start 0.118872 -0.306324)
			(end 0.680466 -0.306324)
			(stroke
				(width 0.1)
				(type default)
			)
			(layer "F.Fab")
		)
		(fp_line
			(start 0.118364 0.306324)
			(end 0.118364 0.2794)
			(stroke
				(width 0.1)
				(type default)
			)
			(layer "F.Fab")
		)
		(fp_line
			(start 0.118364 0.2794)
			(end -0.119634 0.2794)
			(stroke
				(width 0.1)
				(type default)
			)
			(layer "F.Fab")
		)
		(fp_line
			(start -0.118364 -0.2794)
			(end 0.118872 -0.2794)
			(stroke
				(width 0.1)
				(type default)
			)
			(layer "F.Fab")
		)
		(fp_line
			(start -0.118364 -0.307086)
			(end -0.118364 -0.2794)
			(stroke
				(width 0.1)
				(type default)
			)
			(layer "F.Fab")
		)
		(fp_line
			(start -0.119634 0.30607)
			(end -0.681736 0.30607)
			(stroke
				(width 0.1)
				(type default)
			)
			(layer "F.Fab")
		)
		(fp_line
			(start -0.119634 0.2794)
			(end -0.119634 0.30607)
			(stroke
				(width 0.1)
				(type default)
			)
			(layer "F.Fab")
		)
		(fp_line
			(start -0.681736 0.30607)
			(end -0.681736 -0.307086)
			(stroke
				(width 0.1)
				(type default)
			)
			(layer "F.Fab")
		)
		(fp_line
			(start -0.681736 -0.307086)
			(end -0.118364 -0.307086)
			(stroke
				(width 0.1)
				(type default)
			)
			(layer "F.Fab")
		)
		(pad "1" smd rect
			(at -0.40005 0)
			(size 0.4572 0.508)
			(layers "F.Cu" "F.Mask" "F.Paste")
			(net "P1V8_CPU1_RT_1D")
		)
		(pad "2" smd rect
			(at 0.40005 0)
			(size 0.4572 0.508)
			(layers "F.Cu" "F.Mask" "F.Paste")
			(net "P1V8_CPU1_RT1_1A_1D")
		)
	)
	(footprint ""
		(layer "F.Cu")
		(at 257.242056 -121.95937 180)
		(property "Reference" "R3714"
			(at 0 0 180)
			(layer "F.SilkS")
			(hide yes)
			(effects
				(font
					(size 1.27 1.27)
				)
			)
		)
		(property "Value" ""
			(at 0 0 180)
			(layer "F.Fab")
			(effects
				(font
					(size 1.27 1.27)
				)
			)
		)
		(duplicate_pad_numbers_are_jumpers no)
		(fp_line
			(start 0.7874 0.4064)
			(end -0.7874 0.4064)
			(stroke
				(width 0.1524)
				(type default)
			)
			(layer "F.SilkS")
		)
		(fp_line
			(start 0.7874 -0.4064)
			(end 0.7874 0.4064)
			(stroke
				(width 0.1524)
				(type default)
			)
			(layer "F.SilkS")
		)
		(fp_line
			(start -0.7874 0.4064)
			(end -0.7874 -0.4064)
			(stroke
				(width 0.1524)
				(type default)
			)
			(layer "F.SilkS")
		)
		(fp_line
			(start -0.7874 -0.4064)
			(end 0.7874 -0.4064)
			(stroke
				(width 0.1524)
				(type default)
			)
			(layer "F.SilkS")
		)
		(fp_line
			(start 0.67945 0.3048)
			(end 0.120396 0.3048)
			(stroke
				(width 0.1)
				(type default)
			)
			(layer "F.Fab")
		)
		(fp_line
			(start 0.67945 -0.3048)
			(end 0.67945 0.3048)
			(stroke
				(width 0.1)
				(type default)
			)
			(layer "F.Fab")
		)
		(fp_line
			(start 0.12065 -0.2794)
			(end 0.12065 -0.3048)
			(stroke
				(width 0.1)
				(type default)
			)
			(layer "F.Fab")
		)
		(fp_line
			(start 0.12065 -0.3048)
			(end 0.67945 -0.3048)
			(stroke
				(width 0.1)
				(type default)
			)
			(layer "F.Fab")
		)
		(fp_line
			(start 0.120396 0.3048)
			(end 0.120396 0.2794)
			(stroke
				(width 0.1)
				(type default)
			)
			(layer "F.Fab")
		)
		(fp_line
			(start 0.120396 0.2794)
			(end -0.12065 0.2794)
			(stroke
				(width 0.1)
				(type default)
			)
			(layer "F.Fab")
		)
		(fp_line
			(start -0.12065 0.3048)
			(end -0.67945 0.3048)
			(stroke
				(width 0.1)
				(type default)
			)
			(layer "F.Fab")
		)
		(fp_line
			(start -0.12065 0.2794)
			(end -0.12065 0.3048)
			(stroke
				(width 0.1)
				(type default)
			)
			(layer "F.Fab")
		)
		(fp_line
			(start -0.12065 -0.2794)
			(end 0.12065 -0.2794)
			(stroke
				(width 0.1)
				(type default)
			)
			(layer "F.Fab")
		)
		(fp_line
			(start -0.12065 -0.305054)
			(end -0.12065 -0.2794)
			(stroke
				(width 0.1)
				(type default)
			)
			(layer "F.Fab")
		)
		(fp_line
			(start -0.67945 0.3048)
			(end -0.67945 -0.305054)
			(stroke
				(width 0.1)
				(type default)
			)
			(layer "F.Fab")
		)
		(fp_line
			(start -0.67945 -0.305054)
			(end -0.12065 -0.305054)
			(stroke
				(width 0.1)
				(type default)
			)
			(layer "F.Fab")
		)
		(pad "1" smd circle
			(at -0.40005 0 180)
			(size 0 0)
			(layers "F.Cu" "F.Mask" "F.Paste")
			(net "SMB_VR_3V3AUX_SDA_R6")
		)
		(pad "2" smd circle
			(at 0.40005 0 180)
			(size 0 0)
			(layers "F.Cu" "F.Mask" "F.Paste")
			(net "SMB_VR_3V3AUX_SDA")
		)
	)
)
